# TIMECARD (Time Appliance Project (Time Card)) — schematic netlist excerpt (pin names and nets, part order shuffled) for the footprints in the layout excerpt that follows; sources: Cadence DE-HDL packaged netlist, KiCad conversion of R4006-B0001-02_R01.brd

TP21  TP_PIONT  pkg TP010CT020B030_PTH  page 25 : \1\ = PCA9546_RST_N
SP59  NULL  pkg DUMMY  page 34
SP22  SOLDER_PREFORM  pkg 0201_SOLDER_PREFORM_4MIL  page 34 : \1\ = NC ; \2\ = NC
R14  RESISTOR  3.92KOHM 1%  pkg SMC_0402R  page 27 : \1\ = XP12R0V_A_PG ; \2\ = SG

(kicad_pcb
	(version 20260206)
	(generator "pcbnew")
	(generator_version "10.0")
	(general
		(thickness 1.6)
		(legacy_teardrops no)
	)
	(paper "A4")
	(title_block
		(title "timecard-production-celestica-r4006 — R4006-B0001-02_R01.brd")
		(comment 1 "Time Appliance Project (Time Card) / footprints 482-485 of 1113")
	)
	(layers
		(0 "F.Cu" signal "TOP")
		(4 "In1.Cu" signal "L02_GND1")
		(6 "In2.Cu" signal "L03_SIG1")
		(8 "In3.Cu" signal "L04_GND2")
		(10 "In4.Cu" signal "L05_VCC1")
		(12 "In5.Cu" signal "L06_VCC2")
		(14 "In6.Cu" signal "L07_GND3")
		(16 "In7.Cu" signal "L08_SIG2")
		(18 "In8.Cu" signal "L09_GND4")
		(2 "B.Cu" signal "BOTTOM")
		(9 "F.Adhes" user "F.Adhesive")
		(11 "B.Adhes" user "B.Adhesive")
		(13 "F.Paste" user "Package Geometry/Pastemask Top")
		(15 "B.Paste" user "Package Geometry/Pastemask Bottom")
		(5 "F.SilkS" user "Ref Des/Silkscreen Top")
		(7 "B.SilkS" user "Ref Des/Silkscreen Bottom")
		(1 "F.Mask" user "Board Geometry/Soldermask Top")
		(3 "B.Mask" user "Board Geometry/Soldermask Bottom")
		(17 "Dwgs.User" user "User.Drawings")
		(19 "Cmts.User" user "User.Comments")
		(21 "Eco1.User" user "User.Eco1")
		(23 "Eco2.User" user "User.Eco2")
		(25 "Edge.Cuts" user "Board Geometry/Outline")
		(27 "Margin" user)
		(31 "F.CrtYd" user "Package Geometry/Place Bound Top")
		(29 "B.CrtYd" user "Package Geometry/Place Bound Bottom")
		(35 "F.Fab" user "Ref Des/Assembly Top")
		(33 "B.Fab" user "Ref Des/Assembly Bottom")
	)
	(footprint ""
		(layer "F.Cu")
		(at 85.598 -87.376)
		(property "Reference" "TP21"
			(at -1.2192 -1.61163 0)
			(unlocked yes)
			(layer "F.SilkS")
			(effects
				(font
					(size 0.7874 0.5842)
					(thickness 0.1524)
				)
				(justify left)
			)
		)
		(property "Value" ""
			(at 0 0 0)
			(layer "F.Fab")
			(effects
				(font
					(size 1.27 1.27)
				)
			)
		)
		(property "Device Type" "TP_PIONT-TP010CT020B030_PTH-TPA"
			(at -1.341882 0.996696 0)
			(unlocked yes)
			(layer "F.Fab")
			(hide yes)
			(effects
				(font
					(size 0.7874 0.5842)
					(thickness 0.000001)
				)
				(justify left)
			)
		)
		(duplicate_pad_numbers_are_jumpers no)
		(fp_poly
			(pts
				(arc
					(start 0.889 0)
					(mid -0.889 0)
					(end 0.889 0)
				)
			)
			(stroke
				(width 0)
				(type default)
			)
			(fill no)
			(layer "B.CrtYd")
		)
		(fp_poly
			(pts
				(arc
					(start 0.889 0)
					(mid -0.889 0)
					(end 0.889 0)
				)
			)
			(stroke
				(width 0)
				(type default)
			)
			(fill no)
			(layer "F.CrtYd")
		)
		(pad "1" thru_hole circle
			(at 0 0)
			(size 0.508 0.508)
			(drill 0.254)
			(layers "*.Cu" "*.Mask")
			(remove_unused_layers no)
			(net "PCA9546_RST_N")
			(clearance 0.1016)
			(padstack
				(mode front_inner_back)
				(layer "Inner"
					(shape circle)
					(size 0.508 0.508)
					(clearance 0.1016)
				)
				(layer "B.Cu"
					(shape circle)
					(size 0.762 0.762)
					(clearance -0.0254)
				)
			)
		)
	)
	(footprint ""
		(layer "F.Cu")
		(at 57.277 -130.048)
		(property "Reference" "SP59"
			(at 0 0 0)
			(layer "F.SilkS")
			(hide yes)
			(effects
				(font
					(size 1.27 1.27)
				)
			)
		)
		(property "Value" ""
			(at 0 0 0)
			(layer "F.Fab")
			(effects
				(font
					(size 1.27 1.27)
				)
			)
		)
		(duplicate_pad_numbers_are_jumpers no)
	)
	(footprint ""
		(layer "F.Cu")
		(at 42.545 -123.19)
		(property "Reference" "SP22"
			(at 0 0 0)
			(layer "F.SilkS")
			(hide yes)
			(effects
				(font
					(size 1.27 1.27)
				)
			)
		)
		(property "Value" ""
			(at 0 0 0)
			(layer "F.Fab")
			(effects
				(font
					(size 1.27 1.27)
				)
			)
		)
		(duplicate_pad_numbers_are_jumpers no)
	)
	(footprint ""
		(layer "F.Cu")
		(at 141.732 -99.441)
		(property "Reference" "R14"
			(at 2.032 0.92075 0)
			(unlocked yes)
			(layer "F.SilkS")
			(effects
				(font
					(size 0.635 0.4064)
					(thickness 0.1524)
				)
			)
		)
		(property "Value" "VAL*"
			(at 0.0508 2.245106 0)
			(unlocked yes)
			(layer "F.Fab")
			(hide yes)
			(effects
				(font
					(size 0.7874 0.5842)
					(thickness 0.1524)
				)
			)
		)
		(property "Tolerance" "TOL*"
			(at 0.0508 3.261106 0)
			(unlocked yes)
			(layer "Cmts.User")
			(hide yes)
			(effects
				(font
					(size 0.7874 0.5842)
					(thickness 0.1524)
				)
			)
		)
		(property "Device Type" "RESISTOR-G155-03921-01,3.92KOHA"
			(at 0.0762 1.254506 0)
			(unlocked yes)
			(layer "F.Fab")
			(hide yes)
			(effects
				(font
					(size 0.7874 0.5842)
					(thickness 0.1524)
				)
			)
		)
		(property "User Part Number" "PARTNUM*"
			(at 0.0762 4.302506 0)
			(unlocked yes)
			(layer "Cmts.User")
			(hide yes)
			(effects
				(font
					(size 0.7874 0.5842)
					(thickness 0.1524)
				)
			)
		)
		(duplicate_pad_numbers_are_jumpers no)
		(fp_line
			(start -1.143 -0.5588)
			(end -1.143 0.5588)
			(stroke
				(width 0.1)
				(type default)
			)
			(layer "F.SilkS")
		)
		(fp_line
			(start -1.143 0.5588)
			(end 1.143 0.5588)
			(stroke
				(width 0.1)
				(type default)
			)
			(layer "F.SilkS")
		)
		(fp_line
			(start 1.143 -0.5588)
			(end -1.143 -0.5588)
			(stroke
				(width 0.1)
				(type default)
			)
			(layer "F.SilkS")
		)
		(fp_line
			(start 1.143 0.5588)
			(end 1.143 -0.5588)
			(stroke
				(width 0.1)
				(type default)
			)
			(layer "F.SilkS")
		)
		(fp_rect
			(start 1.143 -0.5588)
			(end -1.143 0.5588)
			(stroke
				(width 0)
				(type default)
			)
			(fill no)
			(layer "F.CrtYd")
		)
		(fp_line
			(start -0.508 -0.3048)
			(end -0.508 0.3048)
			(stroke
				(width 0.1)
				(type default)
			)
			(layer "F.Fab")
		)
		(fp_line
			(start -0.508 0.3048)
			(end 0.508 0.3048)
			(stroke
				(width 0.1)
				(type default)
			)
			(layer "F.Fab")
		)
		(fp_line
			(start 0.508 -0.3048)
			(end -0.508 -0.3048)
			(stroke
				(width 0.1)
				(type default)
			)
			(layer "F.Fab")
		)
		(fp_line
			(start 0.508 0.3048)
			(end 0.508 -0.3048)
			(stroke
				(width 0.1)
				(type default)
			)
			(layer "F.Fab")
		)
		(pad "1" smd rect
			(at -0.5334 0)
			(size 0.7112 0.6096)
			(layers "F.Cu" "F.Mask" "F.Paste")
			(net "XP12R0V_A_PG")
		)
		(pad "2" smd rect
			(at 0.5334 0)
			(size 0.7112 0.6096)
			(layers "F.Cu" "F.Mask" "F.Paste")
			(net "SG")
		)
		(zone
			(layer "F.Cu")
			(hatch none 0.5)
			(connect_pads
				(clearance 0)
			)
			(min_thickness 0.25)
			(keepout
				(tracks allowed)
				(vias not_allowed)
				(pads allowed)
				(copperpour not_allowed)
				(footprints allowed)
			)
			(placement
				(enabled no)
				(sheetname "")
			)
			(fill
				(thermal_gap 0.5)
				(thermal_bridge_width 0.5)
				(island_removal_mode 0)
			)
			(polygon
				(pts
					(xy 141.8082 -99.7458) (xy 141.6558 -99.7458) (xy 141.6558 -99.1362) (xy 141.8082 -99.1362)
				)
			)
		)
	)
)
